# T6G (Grand Teton) — schematic netlist excerpt (pin names and nets, part order shuffled) for the footprints in the layout excerpt that follows; sources: Cadence DE-HDL packaged netlist, KiCad conversion of 04192023_DAF0TMB3IC0_F0TG_MB_C_brd_V02_OCP.brd

C6556  Q_CAP_DIFFBUS  DIFF BUS_0.22UF 6.3V 20% X6S  pkg C0201  page 286 : \1\ = P5E_CPU0_P1_TX_BUF_C_DN<11> ; \2\ = P5E_CPU0_P1_TX_BUF_DN<11>
PR364  Q_RES  2.2 1% CHIP  pkg 0402LF  page 199 : A = PVDDCR_CPU0_P0_PVCC ; B = PVDDCR_SOC_P0_VCC3
R520  Q_RES  2.2K 5% CHIP  pkg 0402LF  page 54 : A = CPU1_PROCHOT_N ; B = PVDD18_S5_P1

(kicad_pcb
	(version 20260206)
	(generator "pcbnew")
	(generator_version "10.0")
	(general
		(thickness 1.6)
		(legacy_teardrops no)
	)
	(paper "A4")
	(title_block
		(title "04192023_DAF0TMB3IC0_F0TG_MB_C_brd_V02_OCP.brd")
		(comment 1 "Grand Teton / footprints 7088-7090 of 8354")
	)
	(layers
		(0 "F.Cu" signal "TOP")
		(4 "In1.Cu" signal "GND")
		(6 "In2.Cu" signal "IN1")
		(8 "In3.Cu" signal "GND1")
		(10 "In4.Cu" signal "IN2")
		(12 "In5.Cu" signal "GND2")
		(14 "In6.Cu" signal "IN3")
		(16 "In7.Cu" signal "GND3")
		(18 "In8.Cu" signal "VCC")
		(20 "In9.Cu" signal "VCC1")
		(22 "In10.Cu" signal "GND4")
		(24 "In11.Cu" signal "IN4")
		(26 "In12.Cu" signal "GND5")
		(28 "In13.Cu" signal "IN5")
		(30 "In14.Cu" signal "GND6")
		(32 "In15.Cu" signal "IN6")
		(34 "In16.Cu" signal "GND7")
		(2 "B.Cu" signal "BOTTOM")
		(9 "F.Adhes" user "F.Adhesive")
		(11 "B.Adhes" user "B.Adhesive")
		(13 "F.Paste" user "Package Geometry/Pastemask Top")
		(15 "B.Paste" user "Package Geometry/Pastemask Bottom")
		(5 "F.SilkS" user "Ref Des/Silkscreen Top")
		(7 "B.SilkS" user "Ref Des/Silkscreen Bottom")
		(1 "F.Mask" user "Board Geometry/Soldermask Top")
		(3 "B.Mask" user "Board Geometry/Soldermask Bottom")
		(17 "Dwgs.User" user "User.Drawings")
		(19 "Cmts.User" user "User.Comments")
		(21 "Eco1.User" user "User.Eco1")
		(23 "Eco2.User" user "User.Eco2")
		(25 "Edge.Cuts" user "Board Geometry/Outline")
		(27 "Margin" user)
		(31 "F.CrtYd" user "Package Geometry/Place Bound Top")
		(29 "B.CrtYd" user "Package Geometry/Place Bound Bottom")
		(35 "F.Fab" user "Ref Des/Assembly Top")
		(33 "B.Fab" user "Ref Des/Assembly Bottom")
	)
	(footprint ""
		(layer "B.Cu")
		(at 416.84067 -162.70859 90)
		(property "Reference" "PR364"
			(at 0 0 90)
			(layer "B.SilkS")
			(hide yes)
			(effects
				(font
					(size 1.27 1.27)
				)
				(justify mirror)
			)
		)
		(property "Value" ""
			(at 0 0 90)
			(layer "B.Fab")
			(effects
				(font
					(size 1.27 1.27)
				)
				(justify mirror)
			)
		)
		(duplicate_pad_numbers_are_jumpers no)
		(fp_line
			(start 0.7874 -0.4064)
			(end -0.7874 -0.4064)
			(stroke
				(width 0.1524)
				(type default)
			)
			(layer "B.SilkS")
		)
		(fp_line
			(start -0.7874 -0.4064)
			(end -0.7874 0.4064)
			(stroke
				(width 0.1524)
				(type default)
			)
			(layer "B.SilkS")
		)
		(fp_line
			(start 0.7874 0.4064)
			(end 0.7874 -0.4064)
			(stroke
				(width 0.1524)
				(type default)
			)
			(layer "B.SilkS")
		)
		(fp_line
			(start -0.7874 0.4064)
			(end 0.7874 0.4064)
			(stroke
				(width 0.1524)
				(type default)
			)
			(layer "B.SilkS")
		)
		(fp_line
			(start 0.67945 -0.305054)
			(end 0.12065 -0.305054)
			(stroke
				(width 0.1)
				(type default)
			)
			(layer "B.Fab")
		)
		(fp_line
			(start 0.12065 -0.305054)
			(end 0.12065 -0.2794)
			(stroke
				(width 0.1)
				(type default)
			)
			(layer "B.Fab")
		)
		(fp_line
			(start -0.12065 -0.3048)
			(end -0.67945 -0.3048)
			(stroke
				(width 0.1)
				(type default)
			)
			(layer "B.Fab")
		)
		(fp_line
			(start -0.67945 -0.3048)
			(end -0.67945 0.3048)
			(stroke
				(width 0.1)
				(type default)
			)
			(layer "B.Fab")
		)
		(fp_line
			(start 0.12065 -0.2794)
			(end -0.12065 -0.2794)
			(stroke
				(width 0.1)
				(type default)
			)
			(layer "B.Fab")
		)
		(fp_line
			(start -0.12065 -0.2794)
			(end -0.12065 -0.3048)
			(stroke
				(width 0.1)
				(type default)
			)
			(layer "B.Fab")
		)
		(fp_line
			(start 0.12065 0.2794)
			(end 0.12065 0.3048)
			(stroke
				(width 0.1)
				(type default)
			)
			(layer "B.Fab")
		)
		(fp_line
			(start -0.120396 0.2794)
			(end 0.12065 0.2794)
			(stroke
				(width 0.1)
				(type default)
			)
			(layer "B.Fab")
		)
		(fp_line
			(start 0.67945 0.3048)
			(end 0.67945 -0.305054)
			(stroke
				(width 0.1)
				(type default)
			)
			(layer "B.Fab")
		)
		(fp_line
			(start 0.12065 0.3048)
			(end 0.67945 0.3048)
			(stroke
				(width 0.1)
				(type default)
			)
			(layer "B.Fab")
		)
		(fp_line
			(start -0.120396 0.3048)
			(end -0.120396 0.2794)
			(stroke
				(width 0.1)
				(type default)
			)
			(layer "B.Fab")
		)
		(fp_line
			(start -0.67945 0.3048)
			(end -0.120396 0.3048)
			(stroke
				(width 0.1)
				(type default)
			)
			(layer "B.Fab")
		)
		(pad "1" smd circle
			(at 0.40005 0 270)
			(size 0 0)
			(layers "B.Cu" "B.Mask" "B.Paste")
			(net "PVDDCR_CPU0_P0_PVCC")
		)
		(pad "2" smd circle
			(at -0.40005 0 270)
			(size 0 0)
			(layers "B.Cu" "B.Mask" "B.Paste")
			(net "PVDDCR_SOC_P0_VCC3")
		)
	)
	(footprint ""
		(layer "B.Cu")
		(at 338.995766 -416.899344 90)
		(property "Reference" "C6556"
			(at 0 0 90)
			(layer "B.SilkS")
			(hide yes)
			(effects
				(font
					(size 1.27 1.27)
				)
				(justify mirror)
			)
		)
		(property "Value" ""
			(at 0 0 90)
			(layer "B.Fab")
			(effects
				(font
					(size 1.27 1.27)
				)
				(justify mirror)
			)
		)
		(duplicate_pad_numbers_are_jumpers no)
		(fp_line
			(start 0.299974 -0.150114)
			(end -0.299974 -0.150114)
			(stroke
				(width 0.1)
				(type default)
			)
			(layer "B.Fab")
		)
		(fp_line
			(start -0.299974 -0.150114)
			(end -0.299974 0.150114)
			(stroke
				(width 0.1)
				(type default)
			)
			(layer "B.Fab")
		)
		(fp_line
			(start 0.299974 0.150114)
			(end 0.299974 -0.150114)
			(stroke
				(width 0.1)
				(type default)
			)
			(layer "B.Fab")
		)
		(fp_line
			(start -0.299974 0.150114)
			(end 0.299974 0.150114)
			(stroke
				(width 0.1)
				(type default)
			)
			(layer "B.Fab")
		)
		(pad "1" smd rect
			(at 0.2667 0 270)
			(size 0.3048 0.381)
			(layers "B.Cu" "B.Mask" "B.Paste")
			(net "P5E_CPU0_P1_TX_BUF_C_DN<11>")
		)
		(pad "2" smd rect
			(at -0.2667 0 270)
			(size 0.3048 0.381)
			(layers "B.Cu" "B.Mask" "B.Paste")
			(net "P5E_CPU0_P1_TX_BUF_DN<11>")
		)
	)
	(footprint ""
		(layer "B.Cu")
		(at 59.233562 -190.64732 -90)
		(property "Reference" "R520"
			(at 0 0 90)
			(layer "B.SilkS")
			(hide yes)
			(effects
				(font
					(size 1.27 1.27)
				)
				(justify mirror)
			)
		)
		(property "Value" ""
			(at 0 0 90)
			(layer "B.Fab")
			(effects
				(font
					(size 1.27 1.27)
				)
				(justify mirror)
			)
		)
		(duplicate_pad_numbers_are_jumpers no)
		(fp_line
			(start -0.7874 0.4064)
			(end 0.7874 0.4064)
			(stroke
				(width 0.1524)
				(type default)
			)
			(layer "B.SilkS")
		)
		(fp_line
			(start 0.7874 0.4064)
			(end 0.7874 -0.4064)
			(stroke
				(width 0.1524)
				(type default)
			)
			(layer "B.SilkS")
		)
		(fp_line
			(start -0.7874 -0.4064)
			(end -0.7874 0.4064)
			(stroke
				(width 0.1524)
				(type default)
			)
			(layer "B.SilkS")
		)
		(fp_line
			(start 0.7874 -0.4064)
			(end -0.7874 -0.4064)
			(stroke
				(width 0.1524)
				(type default)
			)
			(layer "B.SilkS")
		)
		(fp_line
			(start -0.67945 0.3048)
			(end -0.120396 0.3048)
			(stroke
				(width 0.1)
				(type default)
			)
			(layer "B.Fab")
		)
		(fp_line
			(start -0.120396 0.3048)
			(end -0.120396 0.2794)
			(stroke
				(width 0.1)
				(type default)
			)
			(layer "B.Fab")
		)
		(fp_line
			(start 0.12065 0.3048)
			(end 0.67945 0.3048)
			(stroke
				(width 0.1)
				(type default)
			)
			(layer "B.Fab")
		)
		(fp_line
			(start 0.67945 0.3048)
			(end 0.67945 -0.305054)
			(stroke
				(width 0.1)
				(type default)
			)
			(layer "B.Fab")
		)
		(fp_line
			(start -0.120396 0.2794)
			(end 0.12065 0.2794)
			(stroke
				(width 0.1)
				(type default)
			)
			(layer "B.Fab")
		)
		(fp_line
			(start 0.12065 0.2794)
			(end 0.12065 0.3048)
			(stroke
				(width 0.1)
				(type default)
			)
			(layer "B.Fab")
		)
		(fp_line
			(start -0.12065 -0.2794)
			(end -0.12065 -0.3048)
			(stroke
				(width 0.1)
				(type default)
			)
			(layer "B.Fab")
		)
		(fp_line
			(start 0.12065 -0.2794)
			(end -0.12065 -0.2794)
			(stroke
				(width 0.1)
				(type default)
			)
			(layer "B.Fab")
		)
		(fp_line
			(start -0.67945 -0.3048)
			(end -0.67945 0.3048)
			(stroke
				(width 0.1)
				(type default)
			)
			(layer "B.Fab")
		)
		(fp_line
			(start -0.12065 -0.3048)
			(end -0.67945 -0.3048)
			(stroke
				(width 0.1)
				(type default)
			)
			(layer "B.Fab")
		)
		(fp_line
			(start 0.12065 -0.305054)
			(end 0.12065 -0.2794)
			(stroke
				(width 0.1)
				(type default)
			)
			(layer "B.Fab")
		)
		(fp_line
			(start 0.67945 -0.305054)
			(end 0.12065 -0.305054)
			(stroke
				(width 0.1)
				(type default)
			)
			(layer "B.Fab")
		)
		(pad "1" smd circle
			(at 0.40005 0 90)
			(size 0 0)
			(layers "B.Cu" "B.Mask" "B.Paste")
			(net "CPU1_PROCHOT_N")
		)
		(pad "2" smd circle
			(at -0.40005 0 90)
			(size 0 0)
			(layers "B.Cu" "B.Mask" "B.Paste")
			(net "PVDD18_S5_P1")
		)
	)
)
